# S9S_MB_2U (Grand Teton) — schematic netlist excerpt (pin names and nets, part order shuffled) for the footprints in the layout excerpt that follows; sources: Cadence DE-HDL packaged netlist, KiCad conversion of 03242023_DA0F0TMBIJ0_F0T_Motherboard_J_brd_V01_OCP.brd

C1044  Q_CAP  22UF 4V 20% X6S  pkg C0402  page 74 : A = PVCCIN_CPU0 ; B = GND

(kicad_pcb
	(version 20260206)
	(generator "pcbnew")
	(generator_version "10.0")
	(general
		(thickness 1.6)
		(legacy_teardrops no)
	)
	(paper "A4")
	(title_block
		(title "03242023_DA0F0TMBIJ0_F0T_Motherboard_J_brd_V01_OCP.brd")
		(comment 1 "Grand Teton / footprints 1697-1697 of 6105")
	)
	(layers
		(0 "F.Cu" signal "TOP")
		(4 "In1.Cu" signal "GND")
		(6 "In2.Cu" signal "IN1")
		(8 "In3.Cu" signal "GND1")
		(10 "In4.Cu" signal "IN2")
		(12 "In5.Cu" signal "GND2")
		(14 "In6.Cu" signal "IN3")
		(16 "In7.Cu" signal "GND3")
		(18 "In8.Cu" signal "VCC")
		(20 "In9.Cu" signal "VCC1")
		(22 "In10.Cu" signal "GND4")
		(24 "In11.Cu" signal "IN4")
		(26 "In12.Cu" signal "GND5")
		(28 "In13.Cu" signal "IN5")
		(30 "In14.Cu" signal "GND6")
		(32 "In15.Cu" signal "IN6")
		(34 "In16.Cu" signal "GND7")
		(2 "B.Cu" signal "BOTTOM")
		(9 "F.Adhes" user "F.Adhesive")
		(11 "B.Adhes" user "B.Adhesive")
		(13 "F.Paste" user "Package Geometry/Pastemask Top")
		(15 "B.Paste" user "Package Geometry/Pastemask Bottom")
		(5 "F.SilkS" user "Ref Des/Silkscreen Top")
		(7 "B.SilkS" user "Ref Des/Silkscreen Bottom")
		(1 "F.Mask" user "Board Geometry/Soldermask Top")
		(3 "B.Mask" user "Board Geometry/Soldermask Bottom")
		(17 "Dwgs.User" user "User.Drawings")
		(19 "Cmts.User" user "User.Comments")
		(21 "Eco1.User" user "User.Eco1")
		(23 "Eco2.User" user "User.Eco2")
		(25 "Edge.Cuts" user "Board Geometry/Outline")
		(27 "Margin" user)
		(31 "F.CrtYd" user "Package Geometry/Place Bound Top")
		(29 "B.CrtYd" user "Package Geometry/Place Bound Bottom")
		(35 "F.Fab" user "Ref Des/Assembly Top")
		(33 "B.Fab" user "Ref Des/Assembly Bottom")
	)
	(footprint ""
		(layer "F.Cu")
		(at 367.44783 -251.375418 90)
		(property "Reference" "C1044"
			(at 0 0 90)
			(layer "F.SilkS")
			(hide yes)
			(effects
				(font
					(size 1.27 1.27)
				)
			)
		)
		(property "Value" ""
			(at 0 0 90)
			(layer "F.Fab")
			(effects
				(font
					(size 1.27 1.27)
				)
			)
		)
		(duplicate_pad_numbers_are_jumpers no)
		(fp_line
			(start 0.7874 -0.4064)
			(end 0.7874 0.4064)
			(stroke
				(width 0.1524)
				(type default)
			)
			(layer "F.SilkS")
		)
		(fp_line
			(start -0.7874 -0.4064)
			(end 0.7874 -0.4064)
			(stroke
				(width 0.1524)
				(type default)
			)
			(layer "F.SilkS")
		)
		(fp_line
			(start 0.7874 0.4064)
			(end -0.7874 0.4064)
			(stroke
				(width 0.1524)
				(type default)
			)
			(layer "F.SilkS")
		)
		(fp_line
			(start -0.7874 0.4064)
			(end -0.7874 -0.4064)
			(stroke
				(width 0.1524)
				(type default)
			)
			(layer "F.SilkS")
		)
		(fp_line
			(start -0.12065 -0.305054)
			(end -0.12065 -0.2794)
			(stroke
				(width 0.1)
				(type default)
			)
			(layer "F.Fab")
		)
		(fp_line
			(start -0.67945 -0.305054)
			(end -0.12065 -0.305054)
			(stroke
				(width 0.1)
				(type default)
			)
			(layer "F.Fab")
		)
		(fp_line
			(start 0.67945 -0.3048)
			(end 0.67945 0.3048)
			(stroke
				(width 0.1)
				(type default)
			)
			(layer "F.Fab")
		)
		(fp_line
			(start 0.12065 -0.3048)
			(end 0.67945 -0.3048)
			(stroke
				(width 0.1)
				(type default)
			)
			(layer "F.Fab")
		)
		(fp_line
			(start 0.12065 -0.2794)
			(end 0.12065 -0.3048)
			(stroke
				(width 0.1)
				(type default)
			)
			(layer "F.Fab")
		)
		(fp_line
			(start -0.12065 -0.2794)
			(end 0.12065 -0.2794)
			(stroke
				(width 0.1)
				(type default)
			)
			(layer "F.Fab")
		)
		(fp_line
			(start 0.120396 0.2794)
			(end -0.12065 0.2794)
			(stroke
				(width 0.1)
				(type default)
			)
			(layer "F.Fab")
		)
		(fp_line
			(start -0.12065 0.2794)
			(end -0.12065 0.3048)
			(stroke
				(width 0.1)
				(type default)
			)
			(layer "F.Fab")
		)
		(fp_line
			(start 0.67945 0.3048)
			(end 0.120396 0.3048)
			(stroke
				(width 0.1)
				(type default)
			)
			(layer "F.Fab")
		)
		(fp_line
			(start 0.120396 0.3048)
			(end 0.120396 0.2794)
			(stroke
				(width 0.1)
				(type default)
			)
			(layer "F.Fab")
		)
		(fp_line
			(start -0.12065 0.3048)
			(end -0.67945 0.3048)
			(stroke
				(width 0.1)
				(type default)
			)
			(layer "F.Fab")
		)
		(fp_line
			(start -0.67945 0.3048)
			(end -0.67945 -0.305054)
			(stroke
				(width 0.1)
				(type default)
			)
			(layer "F.Fab")
		)
		(pad "1" smd circle
			(at -0.40005 0 90)
			(size 0 0)
			(layers "F.Cu" "F.Mask" "F.Paste")
			(net "PVCCIN_CPU0")
		)
		(pad "2" smd circle
			(at 0.40005 0 90)
			(size 0 0)
			(layers "F.Cu" "F.Mask" "F.Paste")
			(net "GND")
		)
	)
)
